# S9S_MB_2U (Grand Teton) — schematic netlist excerpt (pin names and nets, part order shuffled) for the footprints in the layout excerpt that follows; sources: Cadence DE-HDL packaged netlist, KiCad conversion of 03242023_DA0F0TMBIJ0_F0T_Motherboard_J_brd_V01_OCP.brd

J19  SCONN288_ADR50017P130CC  SCONN288_ADR50017-P130CC IO  pkg DDR288S_1-1VXB  page 100
  VIN_BULK0  = P12V_S3_AUX_CPU1_NVDIMM
  RFU0  = TP_CHB_CPU1_DIMM1_FRU_0
  VIN_MGMT  = P3V3_AUX
  HSCL  = I3C_SPD_DDRABCD_CPU1_LVC1_SCL_2
  HSDA  = I3C_SPD_DDRABCD_CPU1_LVC1_SDA
  VSS0  = GND
  DQ0_A  = M_B_CPU1_SA_DQ<0>
  VSS1  = GND
  DQ1_A  = M_B_CPU1_SA_DQ<1>
  VSS2  = GND
  DQS0_A_T  = M_B_CPU1_SA_DQS_DP<0>
  DQS0_A_C  = M_B_CPU1_SA_DQS_DN<0>
  VSS3  = GND
  DQ4_A  = M_B_CPU1_SA_DQ<4>
  VSS4  = GND
  DQ5_A  = M_B_CPU1_SA_DQ<5>
  VSS5  = GND
  DQ8_A  = M_B_CPU1_SA_DQ<8>
  VSS6  = GND
  DQ9_A  = M_B_CPU1_SA_DQ<9>
  VSS7  = GND
  DQS1_A_T  = M_B_CPU1_SA_DQS_DP<1>
  DQS1_A_C  = M_B_CPU1_SA_DQS_DN<1>
  VSS8  = GND
  DQ12_A  = M_B_CPU1_SA_DQ<12>
  VSS9  = GND
  DQ13_A  = M_B_CPU1_SA_DQ<13>
  VSS10  = GND
  DQ16_A  = M_B_CPU1_SA_DQ<16>
  VSS11  = GND
  DQ17_A  = M_B_CPU1_SA_DQ<17>
  VSS12  = GND
  DQS2_A_T  = M_B_CPU1_SA_DQS_DP<2>
  DQS2_A_C  = M_B_CPU1_SA_DQS_DN<2>
  VSS13  = GND
  DQ20_A  = M_B_CPU1_SA_DQ<20>
  VSS14  = GND
  DQ21_A  = M_B_CPU1_SA_DQ<21>
  VSS15  = GND
  DQ24_A  = M_B_CPU1_SA_DQ<24>
  VSS16  = GND
  DQ25_A  = M_B_CPU1_SA_DQ<25>
  VSS17  = GND
  DQS3_A_T  = M_B_CPU1_SA_DQS_DP<3>
  DQS3_A_C  = M_B_CPU1_SA_DQS_DN<3>
  VSS18  = GND
  DQ28_A  = M_B_CPU1_SA_DQ<28>
  VSS19  = GND
  DQ29_A  = M_B_CPU1_SA_DQ<29>
  VSS20  = GND
  CB0_A  = M_B_CPU1_SA_CB<0>
  VSS21  = GND
  CB1_A  = M_B_CPU1_SA_CB<1>
  VSS22  = GND
  DQS4_A_T  = M_B_CPU1_SA_DQS_DP<4>
  DQS4_A_C  = M_B_CPU1_SA_DQS_DN<4>
  VSS23  = GND
  CB4_A  = M_B_CPU1_SA_CB<4>
  VSS24  = GND
  CB5_A  = M_B_CPU1_SA_CB<5>
  VSS25  = GND
  ALERT_N  = M_B_CPU1_ALERT_N
  VSS26  = GND
  CS0_A_N  = M_B_CPU1_SA_CS_N<0>
  VSS27  = GND
  CA0_A  = M_B_CPU1_SA_CA<0>
  VSS28  = GND
  CA2_A  = M_B_CPU1_SA_CA<2>
  VSS29  = GND
  CA4_A  = M_B_CPU1_SA_CA<4>
  VSS30  = GND
  CA6_A  = M_B_CPU1_SA_CA<6>
  VSS31  = GND
  PAR_A  = M_B_CPU1_SA_PAR
  VSS32  = GND
  CA0_B  = M_B_CPU1_SB_CA<0>
  VSS33  = GND
  CA2_B  = M_B_CPU1_SB_CA<2>
  VSS34  = GND
  CA4_B  = M_B_CPU1_SB_CA<4>
  VSS35  = GND
  CA6_B  = M_B_CPU1_SB_CA<6>
  VSS36  = GND
  CS0_B_N  = M_B_CPU1_SB_CS_N<0>
  VSS37  = GND
  \lbd||rsp_a_n\  = M_B_CPU1_SA_RSP<0>
  \lbs||rsp_b_n\  = M_B_CPU1_SB_RSP<0>
  VSS38  = GND
  CB4_B  = M_B_CPU1_SB_CB<4>
  VSS39  = GND
  CB5_B  = M_B_CPU1_SB_CB<5>
  VSS40  = GND
  \dqs9_b_t||tdqs9_b_t||dbi4_b_n\  = M_B_CPU1_SB_DQS_DP<9>
  \dqs9_b_c||tdqs9_b_c\  = M_B_CPU1_SB_DQS_DN<9>
  VSS41  = GND
  CB0_B  = M_B_CPU1_SB_CB<0>
  VSS42  = GND
  CB1_B  = M_B_CPU1_SB_CB<1>
  VSS43  = GND
  DQ0_B  = M_B_CPU1_SB_DQ<0>
  VSS44  = GND
  DQ1_B  = M_B_CPU1_SB_DQ<1>
  VSS45  = GND
  DQS0_B_T  = M_B_CPU1_SB_DQS_DP<0>
  DQS0_B_C  = M_B_CPU1_SB_DQS_DN<0>
  VSS46  = GND
  DQ4_B  = M_B_CPU1_SB_DQ<4>
  VSS47  = GND
  DQ5_B  = M_B_CPU1_SB_DQ<5>
  VSS48  = GND
  DQ8_B  = M_B_CPU1_SB_DQ<8>
  VSS49  = GND
  DQ9_B  = M_B_CPU1_SB_DQ<9>
  VSS50  = GND
  DQS1_B_T  = M_B_CPU1_SB_DQS_DP<1>
  DQS1_B_C  = M_B_CPU1_SB_DQS_DN<1>
  VSS51  = GND
  DQ12_B  = M_B_CPU1_SB_DQ<12>
  VSS52  = GND
  DQ13_B  = M_B_CPU1_SB_DQ<13>
  VSS53  = GND
  DQ16_B  = M_B_CPU1_SB_DQ<16>
  VSS54  = GND
  DQ17_B  = M_B_CPU1_SB_DQ<17>
  VSS55  = GND
  DQS2_B_T  = M_B_CPU1_SB_DQS_DP<2>
  DQS2_B_C  = M_B_CPU1_SB_DQS_DN<2>
  VSS56  = GND
  DQ20_B  = M_B_CPU1_SB_DQ<20>
  VSS57  = GND
  DQ21_B  = M_B_CPU1_SB_DQ<21>
  VSS58  = GND
  DQ24_B  = M_B_CPU1_SB_DQ<24>
  VSS59  = GND
  DQ25_B  = M_B_CPU1_SB_DQ<25>
  VSS60  = GND
  DQS3_B_T  = M_B_CPU1_SB_DQS_DP<3>
  DQS3_B_C  = M_B_CPU1_SB_DQS_DN<3>
  VSS61  = GND
  DQ28_B  = M_B_CPU1_SB_DQ<28>
  VSS62  = GND
  DQ29_B  = M_B_CPU1_SB_DQ<29>
  VSS63  = GND
  RFU1  = TP_CHB_CPU1_DIMM1_FRU_1
  VIN_BULK1  = P12V_S3_AUX_CPU1_NVDIMM
  VIN_BULK2  = P12V_S3_AUX_CPU1_NVDIMM
  \pwr_good||fail_n\  = PWRGD_CHB_CPU1_DIMM1
  HSA  = PD_CHB_CPU1_DIMM1_SAA
  RFU2  = TP_CHB_CPU1_DIMM1_FRU_2
  RFU3  = TP_CHB_CPU1_DIMM1_FRU_3
  VSS64  = GND
  DQ2_A  = M_B_CPU1_SA_DQ<2>
  VSS65  = GND
  DQ3_A  = M_B_CPU1_SA_DQ<3>
  VSS66  = GND
  \dqs5_a_c||tdqs5_a_c||dqs5_a_t||tdqs5_a_t\  = M_B_CPU1_SA_DQS_DN<5>
  \dqs5_a_t||tdqs5_a_t\  = M_B_CPU1_SA_DQS_DP<5>
  VSS67  = GND
  DQ6_A  = M_B_CPU1_SA_DQ<6>
  VSS68  = GND
  DQ7_A  = M_B_CPU1_SA_DQ<7>
  VSS69  = GND
  DQ10_A  = M_B_CPU1_SA_DQ<10>
  VSS70  = GND
  DQ11_A  = M_B_CPU1_SA_DQ<11>
  VSS71  = GND
  \dqs6_a_c||tdqs6_a_c||dqs6_a_t||tdqs6_a_t\  = M_B_CPU1_SA_DQS_DN<6>
  \dqs6_a_t||tdqs6_a_t\  = M_B_CPU1_SA_DQS_DP<6>
  VSS72  = GND
  DQ14_A  = M_B_CPU1_SA_DQ<14>
  VSS73  = GND
  DQ15_A  = M_B_CPU1_SA_DQ<15>
  VSS74  = GND
  DQ18_A  = M_B_CPU1_SA_DQ<18>
  VSS75  = GND
  DQ19_A  = M_B_CPU1_SA_DQ<19>
  VSS76  = GND
  \dqs7_a_c||tdqs7_a_c\  = M_B_CPU1_SA_DQS_DN<7>
  \dqs7_a_t||tdqs7_a_t\  = M_B_CPU1_SA_DQS_DP<7>
  VSS77  = GND
  DQ22_A  = M_B_CPU1_SA_DQ<22>
  VSS78  = GND
  DQ23_A  = M_B_CPU1_SA_DQ<23>
  VSS79  = GND
  DQ26_A  = M_B_CPU1_SA_DQ<26>
  VSS80  = GND
  DQ27_A  = M_B_CPU1_SA_DQ<27>
  VSS81  = GND
  \dqs8_a_c||tdqs8_a_c\  = M_B_CPU1_SA_DQS_DN<8>
  \dqs8_a_t||tdqs8_a_t\  = M_B_CPU1_SA_DQS_DP<8>
  VSS82  = GND
  DQ30_A  = M_B_CPU1_SA_DQ<30>
  VSS83  = GND
  DQ31_A  = M_B_CPU1_SA_DQ<31>
  VSS84  = GND
  CB2_A  = M_B_CPU1_SA_CB<2>
  VSS85  = GND
  CB3_A  = M_B_CPU1_SA_CB<3>
  VSS86  = GND
  \dqs9_a_c||tdqs9_a_c\  = M_B_CPU1_SA_DQS_DN<9>
  \dqs9_a_t||tdqs9_a_t\  = M_B_CPU1_SA_DQS_DP<9>
  VSS87  = GND
  CB6_A  = M_B_CPU1_SA_CB<6>
  VSS88  = GND
  CB7_A  = M_B_CPU1_SA_CB<7>
  VSS89  = GND
  RESET_N  = RST_M_AB_CPU1_FPGA_N
  VSS90  = GND
  CS1_A_N  = M_B_CPU1_SA_CS_N<1>
  VSS91  = GND
  CA1_A  = M_B_CPU1_SA_CA<1>
  VSS92  = GND
  CA3_A  = M_B_CPU1_SA_CA<3>
  VSS93  = GND
  CA5_A  = M_B_CPU1_SA_CA<5>
  VSS94  = GND
  CK_T  = M_B_CPU1_CLK_DP<0>
  CK_C  = M_B_CPU1_CLK_DN<0>
  VSS95  = GND
  RFU4  = TP_CHB_CPU1_DIMM1_FRU_4
  CA1_B  = M_B_CPU1_SB_CA<1>
  VSS96  = GND
  CA3_B  = M_B_CPU1_SB_CA<3>
  VSS97  = GND
  CA5_B  = M_B_CPU1_SB_CA<5>
  VSS98  = GND
  PAR_B  = M_B_CPU1_SB_PAR
  VSS99  = GND
  CS1_B_N  = M_B_CPU1_SB_CS_N<1>
  VSS100  = GND
  RFU5  = TP_CHB_CPU1_DIMM1_FRU_5
  RFU6  = TP_CHB_CPU1_DIMM1_FRU_6
  VSS101  = GND
  CB6_B  = M_B_CPU1_SB_CB<6>
  VSS102  = GND
  CB7_B  = M_B_CPU1_SB_CB<7>
  VSS103  = GND
  DQS4_B_C  = M_B_CPU1_SB_DQS_DN<4>
  DQS4_B_T  = M_B_CPU1_SB_DQS_DP<4>
  VSS104  = GND
  CB2_B  = M_B_CPU1_SB_CB<2>
  VSS105  = GND
  CB3_B  = M_B_CPU1_SB_CB<3>
  VSS106  = GND
  DQ2_B  = M_B_CPU1_SB_DQ<2>
  VSS107  = GND
  DQ3_B  = M_B_CPU1_SB_DQ<3>
  VSS108  = GND
  \dqs5_b_c||tdqs5_b_c\  = M_B_CPU1_SB_DQS_DN<5>
  \dqs5_b_t||tdqs5_b_t\  = M_B_CPU1_SB_DQS_DP<5>
  VSS109  = GND
  DQ6_B  = M_B_CPU1_SB_DQ<6>
  VSS110  = GND
  DQ7_B  = M_B_CPU1_SB_DQ<7>
  VSS111  = GND
  DQ10_B  = M_B_CPU1_SB_DQ<10>
  VSS112  = GND
  DQ11_B  = M_B_CPU1_SB_DQ<11>
  VSS113  = GND
  \dqs6_b_c||tdqs6_b_c\  = M_B_CPU1_SB_DQS_DN<6>
  \dqs6_b_t||tdqs6_b_t\  = M_B_CPU1_SB_DQS_DP<6>
  VSS114  = GND
  DQ14_B  = M_B_CPU1_SB_DQ<14>
  VSS115  = GND
  DQ15_B  = M_B_CPU1_SB_DQ<15>
  VSS116  = GND
  DQ18_B  = M_B_CPU1_SB_DQ<18>
  VSS117  = GND
  DQ19_B  = M_B_CPU1_SB_DQ<19>
  VSS118  = GND
  \dqs7_b_c||tdqs7_b_c\  = M_B_CPU1_SB_DQS_DN<7>
  \dqs7_b_t||tdqs7_b_t\  = M_B_CPU1_SB_DQS_DP<7>
  VSS119  = GND
  DQ22_B  = M_B_CPU1_SB_DQ<22>
  VSS120  = GND
  DQ23_B  = M_B_CPU1_SB_DQ<23>
  VSS121  = GND
  DQ26_B  = M_B_CPU1_SB_DQ<26>
  VSS122  = GND
  DQ27_B  = M_B_CPU1_SB_DQ<27>
  VSS123  = GND
  \dqs8_b_c||tdqs8_b_c\  = M_B_CPU1_SB_DQS_DN<8>
  \dqs8_b_t||tdqs8_b_t\  = M_B_CPU1_SB_DQS_DP<8>
  VSS124  = GND
  DQ30_B  = M_B_CPU1_SB_DQ<30>
  VSS125  = GND
  DQ31_B  = M_B_CPU1_SB_DQ<31>
  VSS126  = GND
  G1  = GND
  G2  = GND
  G3  = GND

(kicad_pcb
	(version 20260206)
	(generator "pcbnew")
	(generator_version "10.0")
	(general
		(thickness 1.6)
		(legacy_teardrops no)
	)
	(paper "A4")
	(title_block
		(title "03242023_DA0F0TMBIJ0_F0T_Motherboard_J_brd_V01_OCP.brd")
		(comment 1 "Grand Teton / footprint 2188 of 6105 (J19), pads 275-291 of 291")
	)
	(layers
		(0 "F.Cu" signal "TOP")
		(4 "In1.Cu" signal "GND")
		(6 "In2.Cu" signal "IN1")
		(8 "In3.Cu" signal "GND1")
		(10 "In4.Cu" signal "IN2")
		(12 "In5.Cu" signal "GND2")
		(14 "In6.Cu" signal "IN3")
		(16 "In7.Cu" signal "GND3")
		(18 "In8.Cu" signal "VCC")
		(20 "In9.Cu" signal "VCC1")
		(22 "In10.Cu" signal "GND4")
		(24 "In11.Cu" signal "IN4")
		(26 "In12.Cu" signal "GND5")
		(28 "In13.Cu" signal "IN5")
		(30 "In14.Cu" signal "GND6")
		(32 "In15.Cu" signal "IN6")
		(34 "In16.Cu" signal "GND7")
		(2 "B.Cu" signal "BOTTOM")
		(9 "F.Adhes" user "F.Adhesive")
		(11 "B.Adhes" user "B.Adhesive")
		(13 "F.Paste" user "Package Geometry/Pastemask Top")
		(15 "B.Paste" user "Package Geometry/Pastemask Bottom")
		(5 "F.SilkS" user "Ref Des/Silkscreen Top")
		(7 "B.SilkS" user "Ref Des/Silkscreen Bottom")
		(1 "F.Mask" user "Board Geometry/Soldermask Top")
		(3 "B.Mask" user "Board Geometry/Soldermask Bottom")
		(17 "Dwgs.User" user "User.Drawings")
		(19 "Cmts.User" user "User.Comments")
		(21 "Eco1.User" user "User.Eco1")
		(23 "Eco2.User" user "User.Eco2")
		(25 "Edge.Cuts" user "Board Geometry/Outline")
		(27 "Margin" user)
		(31 "F.CrtYd" user "Package Geometry/Place Bound Top")
		(29 "B.CrtYd" user "Package Geometry/Place Bound Bottom")
		(35 "F.Fab" user "Ref Des/Assembly Top")
		(33 "B.Fab" user "Ref Des/Assembly Bottom")
	)
	(footprint ""
		(layer "F.Cu")
		(at 40.36568 -258.091686)
		(property "Reference" "J19"
			(at -5.21716 -81.970372 0)
			(unlocked yes)
			(layer "F.SilkS")
			(effects
				(font
					(size 0.7874 0.5842)
					(thickness 0.1524)
				)
				(justify left)
			)
		)
		(property "Value" ""
			(at 0 0 0)
			(layer "F.Fab")
			(effects
				(font
					(size 1.27 1.27)
				)
			)
		)
		(duplicate_pad_numbers_are_jumpers no)
		(pad "275" smd rect
			(at 2.050034 52.274978 270)
			(size 0.519938 1.4986)
			(layers "F.Cu" "F.Mask" "F.Paste")
			(net "GND")
		)
		(pad "276" smd rect
			(at 2.050034 53.125116 270)
			(size 0.519938 1.4986)
			(layers "F.Cu" "F.Mask" "F.Paste")
			(net "M_B_CPU1_SB_DQ<23>")
		)
		(pad "277" smd rect
			(at 2.050034 53.975 270)
			(size 0.519938 1.4986)
			(layers "F.Cu" "F.Mask" "F.Paste")
			(net "GND")
		)
		(pad "278" smd rect
			(at 2.050034 54.824884 270)
			(size 0.519938 1.4986)
			(layers "F.Cu" "F.Mask" "F.Paste")
			(net "M_B_CPU1_SB_DQ<26>")
		)
		(pad "279" smd rect
			(at 2.050034 55.675022 270)
			(size 0.519938 1.4986)
			(layers "F.Cu" "F.Mask" "F.Paste")
			(net "GND")
		)
		(pad "280" smd rect
			(at 2.050034 56.524906 270)
			(size 0.519938 1.4986)
			(layers "F.Cu" "F.Mask" "F.Paste")
			(net "M_B_CPU1_SB_DQ<27>")
		)
		(pad "281" smd rect
			(at 2.050034 57.375044 270)
			(size 0.519938 1.4986)
			(layers "F.Cu" "F.Mask" "F.Paste")
			(net "GND")
		)
		(pad "282" smd rect
			(at 2.050034 58.224928 270)
			(size 0.519938 1.4986)
			(layers "F.Cu" "F.Mask" "F.Paste")
			(net "M_B_CPU1_SB_DQS_DN<8>")
		)
		(pad "283" smd rect
			(at 2.050034 59.075066 270)
			(size 0.519938 1.4986)
			(layers "F.Cu" "F.Mask" "F.Paste")
			(net "M_B_CPU1_SB_DQS_DP<8>")
		)
		(pad "284" smd rect
			(at 2.050034 59.92495 270)
			(size 0.519938 1.4986)
			(layers "F.Cu" "F.Mask" "F.Paste")
			(net "GND")
		)
		(pad "285" smd rect
			(at 2.050034 60.775088 270)
			(size 0.519938 1.4986)
			(layers "F.Cu" "F.Mask" "F.Paste")
			(net "M_B_CPU1_SB_DQ<30>")
		)
		(pad "286" smd rect
			(at 2.050034 61.624972 270)
			(size 0.519938 1.4986)
			(layers "F.Cu" "F.Mask" "F.Paste")
			(net "GND")
		)
		(pad "287" smd rect
			(at 2.050034 62.47511 270)
			(size 0.519938 1.4986)
			(layers "F.Cu" "F.Mask" "F.Paste")
			(net "M_B_CPU1_SB_DQ<31>")
		)
		(pad "288" smd rect
			(at 2.050034 63.324994 270)
			(size 0.519938 1.4986)
			(layers "F.Cu" "F.Mask" "F.Paste")
			(net "GND")
		)
		(pad "G1" thru_hole oval
			(at 0 -68.97497)
			(size 2.8194 1.5748)
			(drill oval 2.4384 1.1938)
			(layers "*.Cu" "*.Mask")
			(remove_unused_layers no)
			(net "GND")
			(clearance 0.127)
			(thermal_gap 0.127)
		)
		(pad "G2" thru_hole oval
			(at 0 3.875024)
			(size 2.8194 1.5748)
			(drill oval 2.4384 1.1938)
			(layers "*.Cu" "*.Mask")
			(remove_unused_layers no)
			(net "GND")
			(clearance 0.127)
			(thermal_gap 0.127)
		)
		(pad "G3" thru_hole oval
			(at 0 68.97497)
			(size 2.8194 1.5748)
			(drill oval 2.4384 1.1938)
			(layers "*.Cu" "*.Mask")
			(remove_unused_layers no)
			(net "GND")
			(clearance 0.127)
			(thermal_gap 0.127)
		)
	)
)
